Created on vSure / Trilogy - Netlist Compare Summary.

Version 

FTP Site : valor.com
WEB Site : http://www.valor.com 

DATE :  13 Nov 2014
TIME :  17:55:04


     MISMATCH SUMMARY REPORT
     -----------------------

Job  : 13130-1b_200403112      Job  : 13130-1b_200403112
Step : db                      Step : db
Type : CAD                     Type : CURCAD

-----------------------------------------------

 Mismatch Type: shorted

   GND                   -   NET00000            
   AGND_P3V3_STBY        -    "                  
   AGND_P1V0             -    "                  
   AGND_P1V0_STBY        -    "                  
   AGND_P1V8_STBY        -    "                  
   AGND_P1V1             -    "                  
   PV_VDDR               -   NET00029            
   VR_PVDDRA_R_ISUMN1    -    "                  
   VR_PVDDRA_R_IS        -   NET00461            
   VR_PVDDR_A_VSW        -    "                  

 Total : 3
-----------------------------------------------

 Mismatch Type: broken


 Total : 0
-----------------------------------------------

 Mismatch Type: missing


 Total : 0
-----------------------------------------------

 Mismatch Type: extra


 Total : 0
-----------------------------------------------
